(kicad_pcb
	(version 20260206)
	(generator "pcbnew")
	(generator_version "10.0")
	(general
		(thickness 1.6)
		(legacy_teardrops no)
	)
	(paper "A4")
	(title_block
		(title "Bryce Canyon_IOM_IOC_16318-2_OCP.brd")
		(comment 1 "Bryce Canyon / footprints 739-746 of 1605")
	)
	(layers
		(0 "F.Cu" signal "TOP")
		(4 "In1.Cu" signal "L2GND")
		(6 "In2.Cu" signal "L3")
		(8 "In3.Cu" signal "L4VCC")
		(10 "In4.Cu" signal "L5VCC")
		(12 "In5.Cu" signal "L6")
		(14 "In6.Cu" signal "L7GND")
		(2 "B.Cu" signal "BOTTOM")
		(9 "F.Adhes" user "F.Adhesive")
		(11 "B.Adhes" user "B.Adhesive")
		(13 "F.Paste" user "Package Geometry/Pastemask Top")
		(15 "B.Paste" user "Package Geometry/Pastemask Bottom")
		(5 "F.SilkS" user "Ref Des/Silkscreen Top")
		(7 "B.SilkS" user "Ref Des/Silkscreen Bottom")
		(1 "F.Mask" user "Board Geometry/Soldermask Top")
		(3 "B.Mask" user "Board Geometry/Soldermask Bottom")
		(17 "Dwgs.User" user "User.Drawings")
		(19 "Cmts.User" user "User.Comments")
		(21 "Eco1.User" user "User.Eco1")
		(23 "Eco2.User" user "User.Eco2")
		(25 "Edge.Cuts" user "Board Geometry/Outline")
		(27 "Margin" user)
		(31 "F.CrtYd" user "Package Geometry/Place Bound Top")
		(29 "B.CrtYd" user "Package Geometry/Place Bound Bottom")
		(35 "F.Fab" user "Ref Des/Assembly Top")
		(33 "B.Fab" user "Ref Des/Assembly Bottom")
	)
	(footprint ""
		(layer "F.Cu")
		(at 55.0926 -130.547364)
		(property "Reference" "R146"
			(at 0 0 0)
			(layer "F.SilkS")
			(hide yes)
			(effects
				(font
					(size 1.27 1.27)
				)
			)
		)
		(property "Value" "100KR2F-L1-GP"
			(at 0.064008 -3.993896 0)
			(unlocked yes)
			(layer "F.Fab")
			(hide yes)
			(effects
				(font
					(size 1.016 1.016)
					(thickness 0.1524)
				)
			)
		)
		(property "Device Type" "R402H16"
			(at 0.064008 -5.517896 0)
			(unlocked yes)
			(layer "F.Fab")
			(hide yes)
			(effects
				(font
					(size 1.016 1.016)
					(thickness 0.1524)
				)
			)
		)
		(duplicate_pad_numbers_are_jumpers no)
		(fp_line
			(start -0.508 -0.9398)
			(end -0.508 0.9398)
			(stroke
				(width 0.1524)
				(type default)
			)
			(layer "F.SilkS")
		)
		(fp_line
			(start 0.508 -0.9398)
			(end -0.508 -0.9398)
			(stroke
				(width 0.1524)
				(type default)
			)
			(layer "F.SilkS")
		)
		(fp_rect
			(start -0.508 0.9398)
			(end 0.508 -0.9398)
			(stroke
				(width 0)
				(type default)
			)
			(fill no)
			(layer "F.CrtYd")
		)
		(fp_rect
			(start -0.508 0.9398)
			(end 0.508 -0.9398)
			(stroke
				(width 0)
				(type default)
			)
			(fill no)
			(layer "F.Fab")
		)
		(pad "1" smd custom
			(at 0 -0.4445)
			(size 0.1397 0.1397)
			(layers "F.Cu" "F.Mask" "F.Paste")
			(net "LPC_CPU_CLKOUT0")
			(options
				(clearance outline)
				(anchor circle)
			)
			(primitives
				(gr_poly
					(pts
						(arc
							(start -0.1778 -0.2794)
							(mid -0.249642 -0.249642)
							(end -0.2794 -0.1778)
						)
						(arc
							(start -0.2794 0.1778)
							(mid -0.249642 0.249642)
							(end -0.1778 0.2794)
						)
						(arc
							(start 0.1778 0.2794)
							(mid 0.249642 0.249642)
							(end 0.2794 0.1778)
						)
						(arc
							(start 0.2794 -0.1778)
							(mid 0.249642 -0.249642)
							(end 0.1778 -0.2794)
						)
					)
					(width 0)
					(fill yes)
				)
			)
		)
		(pad "2" smd custom
			(at 0 0.4445)
			(size 0.1397 0.1397)
			(layers "F.Cu" "F.Mask" "F.Paste")
			(net "GND")
			(options
				(clearance outline)
				(anchor circle)
			)
			(primitives
				(gr_poly
					(pts
						(arc
							(start -0.1778 -0.2794)
							(mid -0.249642 -0.249642)
							(end -0.2794 -0.1778)
						)
						(arc
							(start -0.2794 0.1778)
							(mid -0.249642 0.249642)
							(end -0.1778 0.2794)
						)
						(arc
							(start 0.1778 0.2794)
							(mid 0.249642 0.249642)
							(end 0.2794 0.1778)
						)
						(arc
							(start 0.2794 -0.1778)
							(mid 0.249642 -0.249642)
							(end 0.1778 -0.2794)
						)
					)
					(width 0)
					(fill yes)
				)
			)
		)
	)
	(footprint ""
		(layer "F.Cu")
		(at 55.1434 -132.1562)
		(property "Reference" "TP11"
			(at 0 0 0)
			(layer "F.SilkS")
			(hide yes)
			(effects
				(font
					(size 1.27 1.27)
				)
			)
		)
		(property "Value" "TPAD28-2-GP"
			(at -0.0127 -1.6637 0)
			(unlocked yes)
			(layer "F.Fab")
			(hide yes)
			(effects
				(font
					(size 1.016 1.016)
					(thickness 0.1524)
				)
			)
		)
		(property "Device Type" "TPAD28"
			(at -0.0127 -3.1877 0)
			(unlocked yes)
			(layer "F.Fab")
			(hide yes)
			(effects
				(font
					(size 1.016 1.016)
					(thickness 0.1524)
				)
			)
		)
		(duplicate_pad_numbers_are_jumpers no)
		(fp_poly
			(pts
				(arc
					(start 0.3556 0)
					(mid -0.3556 0)
					(end 0.3556 0)
				)
			)
			(stroke
				(width 0)
				(type default)
			)
			(fill no)
			(layer "F.CrtYd")
		)
		(fp_poly
			(pts
				(arc
					(start 0.6096 0)
					(mid -0.6096 0)
					(end 0.6096 0)
				)
			)
			(stroke
				(width 0)
				(type default)
			)
			(fill no)
			(layer "F.Fab")
		)
		(pad "1" smd circle
			(at 0 0)
			(size 0.7112 0.7112)
			(layers "F.Cu" "F.Mask" "F.Paste")
			(net "TP_BMC0_LPC_LAD2")
		)
	)
	(footprint ""
		(layer "F.Cu")
		(at 191.8462 -127.635 180)
		(property "Reference" "C281"
			(at 0 0 180)
			(layer "F.SilkS")
			(hide yes)
			(effects
				(font
					(size 1.27 1.27)
				)
			)
		)
		(property "Value" "SC220P50V2KX-3GP"
			(at 1.1811 -2.7051 180)
			(unlocked yes)
			(layer "F.Fab")
			(hide yes)
			(effects
				(font
					(size 1.016 1.016)
					(thickness 0.1524)
				)
			)
		)
		(property "Device Type" "C402H22"
			(at 1.1811 -4.2291 180)
			(unlocked yes)
			(layer "F.Fab")
			(hide yes)
			(effects
				(font
					(size 1.016 1.016)
					(thickness 0.1524)
				)
			)
		)
		(duplicate_pad_numbers_are_jumpers no)
		(fp_rect
			(start -0.4318 0.9525)
			(end 0.4318 -0.9525)
			(stroke
				(width 0)
				(type default)
			)
			(fill no)
			(layer "F.CrtYd")
		)
		(fp_rect
			(start -0.4318 0.9525)
			(end 0.4318 -0.9525)
			(stroke
				(width 0)
				(type default)
			)
			(fill no)
			(layer "F.Fab")
		)
		(pad "1" smd custom
			(at 0 -0.4445 180)
			(size 0.1524 0.1524)
			(layers "F.Cu" "F.Mask" "F.Paste")
			(net "VT235_PGIN")
			(options
				(clearance outline)
				(anchor circle)
			)
			(primitives
				(gr_poly
					(pts
						(arc
							(start 0.3048 -0.2032)
							(mid 0.275042 -0.275042)
							(end 0.2032 -0.3048)
						)
						(arc
							(start -0.2032 -0.3048)
							(mid -0.275042 -0.275042)
							(end -0.3048 -0.2032)
						)
						(arc
							(start -0.3048 0.2032)
							(mid -0.275042 0.275042)
							(end -0.2032 0.3048)
						)
						(arc
							(start 0.2032 0.3048)
							(mid 0.275042 0.275042)
							(end 0.3048 0.2032)
						)
					)
					(width 0)
					(fill yes)
				)
			)
		)
		(pad "2" smd custom
			(at 0 0.4445 180)
			(size 0.1524 0.1524)
			(layers "F.Cu" "F.Mask" "F.Paste")
			(net "VT235_VREF")
			(options
				(clearance outline)
				(anchor circle)
			)
			(primitives
				(gr_poly
					(pts
						(arc
							(start 0.3048 -0.2032)
							(mid 0.275042 -0.275042)
							(end 0.2032 -0.3048)
						)
						(arc
							(start -0.2032 -0.3048)
							(mid -0.275042 -0.275042)
							(end -0.3048 -0.2032)
						)
						(arc
							(start -0.3048 0.2032)
							(mid -0.275042 0.275042)
							(end -0.2032 0.3048)
						)
						(arc
							(start 0.2032 0.3048)
							(mid 0.275042 0.275042)
							(end 0.3048 0.2032)
						)
					)
					(width 0)
					(fill yes)
				)
			)
		)
	)
	(footprint ""
		(layer "F.Cu")
		(at 29.8958 -131.318)
		(property "Reference" "C79"
			(at 0 0 0)
			(layer "F.SilkS")
			(hide yes)
			(effects
				(font
					(size 1.27 1.27)
				)
			)
		)
		(property "Value" "SCD1U16V2KX-3GP"
			(at 1.1811 -2.7051 0)
			(unlocked yes)
			(layer "F.Fab")
			(hide yes)
			(effects
				(font
					(size 1.016 1.016)
					(thickness 0.1524)
				)
			)
		)
		(property "Device Type" "C402H22"
			(at 1.1811 -4.2291 0)
			(unlocked yes)
			(layer "F.Fab")
			(hide yes)
			(effects
				(font
					(size 1.016 1.016)
					(thickness 0.1524)
				)
			)
		)
		(duplicate_pad_numbers_are_jumpers no)
		(fp_rect
			(start -0.4318 0.9525)
			(end 0.4318 -0.9525)
			(stroke
				(width 0)
				(type default)
			)
			(fill no)
			(layer "F.CrtYd")
		)
		(fp_rect
			(start -0.4318 0.9525)
			(end 0.4318 -0.9525)
			(stroke
				(width 0)
				(type default)
			)
			(fill no)
			(layer "F.Fab")
		)
		(pad "1" smd custom
			(at 0 -0.4445)
			(size 0.1524 0.1524)
			(layers "F.Cu" "F.Mask" "F.Paste")
			(net "P3V3_STBY")
			(options
				(clearance outline)
				(anchor circle)
			)
			(primitives
				(gr_poly
					(pts
						(arc
							(start 0.3048 -0.2032)
							(mid 0.275042 -0.275042)
							(end 0.2032 -0.3048)
						)
						(arc
							(start -0.2032 -0.3048)
							(mid -0.275042 -0.275042)
							(end -0.3048 -0.2032)
						)
						(arc
							(start -0.3048 0.2032)
							(mid -0.275042 0.275042)
							(end -0.2032 0.3048)
						)
						(arc
							(start 0.2032 0.3048)
							(mid 0.275042 0.275042)
							(end 0.3048 0.2032)
						)
					)
					(width 0)
					(fill yes)
				)
			)
		)
		(pad "2" smd custom
			(at 0 0.4445)
			(size 0.1524 0.1524)
			(layers "F.Cu" "F.Mask" "F.Paste")
			(net "GND")
			(options
				(clearance outline)
				(anchor circle)
			)
			(primitives
				(gr_poly
					(pts
						(arc
							(start 0.3048 -0.2032)
							(mid 0.275042 -0.275042)
							(end 0.2032 -0.3048)
						)
						(arc
							(start -0.2032 -0.3048)
							(mid -0.275042 -0.275042)
							(end -0.3048 -0.2032)
						)
						(arc
							(start -0.3048 0.2032)
							(mid -0.275042 0.275042)
							(end -0.2032 0.3048)
						)
						(arc
							(start 0.2032 0.3048)
							(mid 0.275042 0.275042)
							(end 0.3048 0.2032)
						)
					)
					(width 0)
					(fill yes)
				)
			)
		)
	)
	(footprint ""
		(layer "F.Cu")
		(at 192.8368 -127.635)
		(property "Reference" "R554"
			(at 0 0 0)
			(layer "F.SilkS")
			(hide yes)
			(effects
				(font
					(size 1.27 1.27)
				)
			)
		)
		(property "Value" "19K1R2F-GP"
			(at 0.064008 -3.993896 0)
			(unlocked yes)
			(layer "F.Fab")
			(hide yes)
			(effects
				(font
					(size 1.016 1.016)
					(thickness 0.1524)
				)
			)
		)
		(property "Device Type" "R402H16"
			(at 0.064008 -5.517896 0)
			(unlocked yes)
			(layer "F.Fab")
			(hide yes)
			(effects
				(font
					(size 1.016 1.016)
					(thickness 0.1524)
				)
			)
		)
		(duplicate_pad_numbers_are_jumpers no)
		(fp_line
			(start -0.508 -0.9398)
			(end -0.508 0.9398)
			(stroke
				(width 0.1524)
				(type default)
			)
			(layer "F.SilkS")
		)
		(fp_line
			(start 0.508 -0.9398)
			(end -0.508 -0.9398)
			(stroke
				(width 0.1524)
				(type default)
			)
			(layer "F.SilkS")
		)
		(fp_rect
			(start -0.508 0.9398)
			(end 0.508 -0.9398)
			(stroke
				(width 0)
				(type default)
			)
			(fill no)
			(layer "F.CrtYd")
		)
		(fp_rect
			(start -0.508 0.9398)
			(end 0.508 -0.9398)
			(stroke
				(width 0)
				(type default)
			)
			(fill no)
			(layer "F.Fab")
		)
		(pad "1" smd custom
			(at 0 -0.4445)
			(size 0.1397 0.1397)
			(layers "F.Cu" "F.Mask" "F.Paste")
			(net "P0V975")
			(options
				(clearance outline)
				(anchor circle)
			)
			(primitives
				(gr_poly
					(pts
						(arc
							(start -0.1778 -0.2794)
							(mid -0.249642 -0.249642)
							(end -0.2794 -0.1778)
						)
						(arc
							(start -0.2794 0.1778)
							(mid -0.249642 0.249642)
							(end -0.1778 0.2794)
						)
						(arc
							(start 0.1778 0.2794)
							(mid 0.249642 0.249642)
							(end 0.2794 0.1778)
						)
						(arc
							(start 0.2794 -0.1778)
							(mid 0.249642 -0.249642)
							(end 0.1778 -0.2794)
						)
					)
					(width 0)
					(fill yes)
				)
			)
		)
		(pad "2" smd custom
			(at 0 0.4445)
			(size 0.1397 0.1397)
			(layers "F.Cu" "F.Mask" "F.Paste")
			(net "VT235_PGIN")
			(options
				(clearance outline)
				(anchor circle)
			)
			(primitives
				(gr_poly
					(pts
						(arc
							(start -0.1778 -0.2794)
							(mid -0.249642 -0.249642)
							(end -0.2794 -0.1778)
						)
						(arc
							(start -0.2794 0.1778)
							(mid -0.249642 0.249642)
							(end -0.1778 0.2794)
						)
						(arc
							(start 0.1778 0.2794)
							(mid 0.249642 0.249642)
							(end 0.2794 0.1778)
						)
						(arc
							(start 0.2794 -0.1778)
							(mid 0.249642 -0.249642)
							(end 0.1778 -0.2794)
						)
					)
					(width 0)
					(fill yes)
				)
			)
		)
	)
	(footprint ""
		(layer "F.Cu")
		(at 54.713124 -162.481768 180)
		(property "Reference" "C118"
			(at 0 0 180)
			(layer "F.SilkS")
			(hide yes)
			(effects
				(font
					(size 1.27 1.27)
				)
			)
		)
		(property "Value" "SCD1U25V2KX-2-GP"
			(at 1.1811 -2.7051 180)
			(unlocked yes)
			(layer "F.Fab")
			(hide yes)
			(effects
				(font
					(size 1.016 1.016)
					(thickness 0.1524)
				)
			)
		)
		(property "Device Type" "C402H22"
			(at 1.1811 -4.2291 180)
			(unlocked yes)
			(layer "F.Fab")
			(hide yes)
			(effects
				(font
					(size 1.016 1.016)
					(thickness 0.1524)
				)
			)
		)
		(duplicate_pad_numbers_are_jumpers no)
		(fp_rect
			(start -0.4318 0.9525)
			(end 0.4318 -0.9525)
			(stroke
				(width 0)
				(type default)
			)
			(fill no)
			(layer "F.CrtYd")
		)
		(fp_rect
			(start -0.4318 0.9525)
			(end 0.4318 -0.9525)
			(stroke
				(width 0)
				(type default)
			)
			(fill no)
			(layer "F.Fab")
		)
		(pad "1" smd custom
			(at 0 -0.4445 180)
			(size 0.1524 0.1524)
			(layers "F.Cu" "F.Mask" "F.Paste")
			(net "ADC_P1V8_STBY")
			(options
				(clearance outline)
				(anchor circle)
			)
			(primitives
				(gr_poly
					(pts
						(arc
							(start 0.3048 -0.2032)
							(mid 0.275042 -0.275042)
							(end 0.2032 -0.3048)
						)
						(arc
							(start -0.2032 -0.3048)
							(mid -0.275042 -0.275042)
							(end -0.3048 -0.2032)
						)
						(arc
							(start -0.3048 0.2032)
							(mid -0.275042 0.275042)
							(end -0.2032 0.3048)
						)
						(arc
							(start 0.2032 0.3048)
							(mid 0.275042 0.275042)
							(end 0.3048 0.2032)
						)
					)
					(width 0)
					(fill yes)
				)
			)
		)
		(pad "2" smd custom
			(at 0 0.4445 180)
			(size 0.1524 0.1524)
			(layers "F.Cu" "F.Mask" "F.Paste")
			(net "GND")
			(options
				(clearance outline)
				(anchor circle)
			)
			(primitives
				(gr_poly
					(pts
						(arc
							(start 0.3048 -0.2032)
							(mid 0.275042 -0.275042)
							(end 0.2032 -0.3048)
						)
						(arc
							(start -0.2032 -0.3048)
							(mid -0.275042 -0.275042)
							(end -0.3048 -0.2032)
						)
						(arc
							(start -0.3048 0.2032)
							(mid -0.275042 0.275042)
							(end -0.2032 0.3048)
						)
						(arc
							(start 0.2032 0.3048)
							(mid 0.275042 0.275042)
							(end 0.3048 0.2032)
						)
					)
					(width 0)
					(fill yes)
				)
			)
		)
	)
	(footprint ""
		(layer "F.Cu")
		(at 189.865 -127.6858 180)
		(property "Reference" "C287"
			(at 0 0 180)
			(layer "F.SilkS")
			(hide yes)
			(effects
				(font
					(size 1.27 1.27)
				)
			)
		)
		(property "Value" "SC1KP50V2KX-1GP"
			(at 1.1811 -2.7051 180)
			(unlocked yes)
			(layer "F.Fab")
			(hide yes)
			(effects
				(font
					(size 1.016 1.016)
					(thickness 0.1524)
				)
			)
		)
		(property "Device Type" "C402H22"
			(at 1.1811 -4.2291 180)
			(unlocked yes)
			(layer "F.Fab")
			(hide yes)
			(effects
				(font
					(size 1.016 1.016)
					(thickness 0.1524)
				)
			)
		)
		(duplicate_pad_numbers_are_jumpers no)
		(fp_rect
			(start -0.4318 0.9525)
			(end 0.4318 -0.9525)
			(stroke
				(width 0)
				(type default)
			)
			(fill no)
			(layer "F.CrtYd")
		)
		(fp_rect
			(start -0.4318 0.9525)
			(end 0.4318 -0.9525)
			(stroke
				(width 0)
				(type default)
			)
			(fill no)
			(layer "F.Fab")
		)
		(pad "1" smd custom
			(at 0 -0.4445 180)
			(size 0.1524 0.1524)
			(layers "F.Cu" "F.Mask" "F.Paste")
			(net "VT235_VREF")
			(options
				(clearance outline)
				(anchor circle)
			)
			(primitives
				(gr_poly
					(pts
						(arc
							(start 0.3048 -0.2032)
							(mid 0.275042 -0.275042)
							(end 0.2032 -0.3048)
						)
						(arc
							(start -0.2032 -0.3048)
							(mid -0.275042 -0.275042)
							(end -0.3048 -0.2032)
						)
						(arc
							(start -0.3048 0.2032)
							(mid -0.275042 0.275042)
							(end -0.2032 0.3048)
						)
						(arc
							(start 0.2032 0.3048)
							(mid 0.275042 0.275042)
							(end 0.3048 0.2032)
						)
					)
					(width 0)
					(fill yes)
				)
			)
		)
		(pad "2" smd custom
			(at 0 0.4445 180)
			(size 0.1524 0.1524)
			(layers "F.Cu" "F.Mask" "F.Paste")
			(net "VT235_VDES_RCC")
			(options
				(clearance outline)
				(anchor circle)
			)
			(primitives
				(gr_poly
					(pts
						(arc
							(start 0.3048 -0.2032)
							(mid 0.275042 -0.275042)
							(end 0.2032 -0.3048)
						)
						(arc
							(start -0.2032 -0.3048)
							(mid -0.275042 -0.275042)
							(end -0.3048 -0.2032)
						)
						(arc
							(start -0.3048 0.2032)
							(mid -0.275042 0.275042)
							(end -0.2032 0.3048)
						)
						(arc
							(start 0.2032 0.3048)
							(mid 0.275042 0.275042)
							(end 0.3048 0.2032)
						)
					)
					(width 0)
					(fill yes)
				)
			)
		)
	)
	(footprint ""
		(layer "F.Cu")
		(at 178.42484 -122.6439)
		(property "Reference" "C510"
			(at 0 0 0)
			(layer "F.SilkS")
			(hide yes)
			(effects
				(font
					(size 1.27 1.27)
				)
			)
		)
		(property "Value" "SCD1U16V2KX-3GP"
			(at 1.1811 -2.7051 0)
			(unlocked yes)
			(layer "F.Fab")
			(hide yes)
			(effects
				(font
					(size 1.016 1.016)
					(thickness 0.1524)
				)
			)
		)
		(property "Device Type" "C402H22"
			(at 1.1811 -4.2291 0)
			(unlocked yes)
			(layer "F.Fab")
			(hide yes)
			(effects
				(font
					(size 1.016 1.016)
					(thickness 0.1524)
				)
			)
		)
		(duplicate_pad_numbers_are_jumpers no)
		(fp_rect
			(start -0.4318 0.9525)
			(end 0.4318 -0.9525)
			(stroke
				(width 0)
				(type default)
			)
			(fill no)
			(layer "F.CrtYd")
		)
		(fp_rect
			(start -0.4318 0.9525)
			(end 0.4318 -0.9525)
			(stroke
				(width 0)
				(type default)
			)
			(fill no)
			(layer "F.Fab")
		)
		(pad "1" smd custom
			(at 0 -0.4445)
			(size 0.1524 0.1524)
			(layers "F.Cu" "F.Mask" "F.Paste")
			(net "P1V8_EN")
			(options
				(clearance outline)
				(anchor circle)
			)
			(primitives
				(gr_poly
					(pts
						(arc
							(start 0.3048 -0.2032)
							(mid 0.275042 -0.275042)
							(end 0.2032 -0.3048)
						)
						(arc
							(start -0.2032 -0.3048)
							(mid -0.275042 -0.275042)
							(end -0.3048 -0.2032)
						)
						(arc
							(start -0.3048 0.2032)
							(mid -0.275042 0.275042)
							(end -0.2032 0.3048)
						)
						(arc
							(start 0.2032 0.3048)
							(mid 0.275042 0.275042)
							(end 0.3048 0.2032)
						)
					)
					(width 0)
					(fill yes)
				)
			)
		)
		(pad "2" smd custom
			(at 0 0.4445)
			(size 0.1524 0.1524)
			(layers "F.Cu" "F.Mask" "F.Paste")
			(net "GND")
			(options
				(clearance outline)
				(anchor circle)
			)
			(primitives
				(gr_poly
					(pts
						(arc
							(start 0.3048 -0.2032)
							(mid 0.275042 -0.275042)
							(end 0.2032 -0.3048)
						)
						(arc
							(start -0.2032 -0.3048)
							(mid -0.275042 -0.275042)
							(end -0.3048 -0.2032)
						)
						(arc
							(start -0.3048 0.2032)
							(mid -0.275042 0.275042)
							(end -0.2032 0.3048)
						)
						(arc
							(start 0.2032 0.3048)
							(mid 0.275042 0.275042)
							(end 0.3048 0.2032)
						)
					)
					(width 0)
					(fill yes)
				)
			)
		)
	)
)
